# S9S_MB_2U (Grand Teton) — schematic netlist excerpt (pin names and nets, part order shuffled) for the footprints in the layout excerpt that follows; sources: Cadence DE-HDL packaged netlist, KiCad conversion of 03242023_DA0F0TMBIJ0_F0T_Motherboard_J_brd_V01_OCP.brd

R761  Q_RES  499 1% CHIP  pkg 0402LF  page 132 : A = PVNN_TERM_CPU0 ; B = DBP_CPU_HOOK9_MBP3_GTL_QS_N

(kicad_pcb
	(version 20260206)
	(generator "pcbnew")
	(generator_version "10.0")
	(general
		(thickness 1.6)
		(legacy_teardrops no)
	)
	(paper "A4")
	(title_block
		(title "03242023_DA0F0TMBIJ0_F0T_Motherboard_J_brd_V01_OCP.brd")
		(comment 1 "Grand Teton / footprints 5930-5930 of 6105")
	)
	(layers
		(0 "F.Cu" signal "TOP")
		(4 "In1.Cu" signal "GND")
		(6 "In2.Cu" signal "IN1")
		(8 "In3.Cu" signal "GND1")
		(10 "In4.Cu" signal "IN2")
		(12 "In5.Cu" signal "GND2")
		(14 "In6.Cu" signal "IN3")
		(16 "In7.Cu" signal "GND3")
		(18 "In8.Cu" signal "VCC")
		(20 "In9.Cu" signal "VCC1")
		(22 "In10.Cu" signal "GND4")
		(24 "In11.Cu" signal "IN4")
		(26 "In12.Cu" signal "GND5")
		(28 "In13.Cu" signal "IN5")
		(30 "In14.Cu" signal "GND6")
		(32 "In15.Cu" signal "IN6")
		(34 "In16.Cu" signal "GND7")
		(2 "B.Cu" signal "BOTTOM")
		(9 "F.Adhes" user "F.Adhesive")
		(11 "B.Adhes" user "B.Adhesive")
		(13 "F.Paste" user "Package Geometry/Pastemask Top")
		(15 "B.Paste" user "Package Geometry/Pastemask Bottom")
		(5 "F.SilkS" user "Ref Des/Silkscreen Top")
		(7 "B.SilkS" user "Ref Des/Silkscreen Bottom")
		(1 "F.Mask" user "Board Geometry/Soldermask Top")
		(3 "B.Mask" user "Board Geometry/Soldermask Bottom")
		(17 "Dwgs.User" user "User.Drawings")
		(19 "Cmts.User" user "User.Comments")
		(21 "Eco1.User" user "User.Eco1")
		(23 "Eco2.User" user "User.Eco2")
		(25 "Edge.Cuts" user "Board Geometry/Outline")
		(27 "Margin" user)
		(31 "F.CrtYd" user "Package Geometry/Place Bound Top")
		(29 "B.CrtYd" user "Package Geometry/Place Bound Bottom")
		(35 "F.Fab" user "Ref Des/Assembly Top")
		(33 "B.Fab" user "Ref Des/Assembly Bottom")
	)
	(footprint ""
		(layer "B.Cu")
		(at 69.353684 -185.791856 90)
		(property "Reference" "R761"
			(at 0 0 90)
			(layer "B.SilkS")
			(hide yes)
			(effects
				(font
					(size 1.27 1.27)
				)
				(justify mirror)
			)
		)
		(property "Value" ""
			(at 0 0 90)
			(layer "B.Fab")
			(effects
				(font
					(size 1.27 1.27)
				)
				(justify mirror)
			)
		)
		(duplicate_pad_numbers_are_jumpers no)
		(fp_line
			(start 0.7874 -0.4064)
			(end -0.7874 -0.4064)
			(stroke
				(width 0.1524)
				(type default)
			)
			(layer "B.SilkS")
		)
		(fp_line
			(start -0.7874 -0.4064)
			(end -0.7874 0.4064)
			(stroke
				(width 0.1524)
				(type default)
			)
			(layer "B.SilkS")
		)
		(fp_line
			(start 0.7874 0.4064)
			(end 0.7874 -0.4064)
			(stroke
				(width 0.1524)
				(type default)
			)
			(layer "B.SilkS")
		)
		(fp_line
			(start -0.7874 0.4064)
			(end 0.7874 0.4064)
			(stroke
				(width 0.1524)
				(type default)
			)
			(layer "B.SilkS")
		)
		(fp_line
			(start 0.67945 -0.305054)
			(end 0.12065 -0.305054)
			(stroke
				(width 0.1)
				(type default)
			)
			(layer "B.Fab")
		)
		(fp_line
			(start 0.12065 -0.305054)
			(end 0.12065 -0.2794)
			(stroke
				(width 0.1)
				(type default)
			)
			(layer "B.Fab")
		)
		(fp_line
			(start -0.12065 -0.3048)
			(end -0.67945 -0.3048)
			(stroke
				(width 0.1)
				(type default)
			)
			(layer "B.Fab")
		)
		(fp_line
			(start -0.67945 -0.3048)
			(end -0.67945 0.3048)
			(stroke
				(width 0.1)
				(type default)
			)
			(layer "B.Fab")
		)
		(fp_line
			(start 0.12065 -0.2794)
			(end -0.12065 -0.2794)
			(stroke
				(width 0.1)
				(type default)
			)
			(layer "B.Fab")
		)
		(fp_line
			(start -0.12065 -0.2794)
			(end -0.12065 -0.3048)
			(stroke
				(width 0.1)
				(type default)
			)
			(layer "B.Fab")
		)
		(fp_line
			(start 0.12065 0.2794)
			(end 0.12065 0.3048)
			(stroke
				(width 0.1)
				(type default)
			)
			(layer "B.Fab")
		)
		(fp_line
			(start -0.120396 0.2794)
			(end 0.12065 0.2794)
			(stroke
				(width 0.1)
				(type default)
			)
			(layer "B.Fab")
		)
		(fp_line
			(start 0.67945 0.3048)
			(end 0.67945 -0.305054)
			(stroke
				(width 0.1)
				(type default)
			)
			(layer "B.Fab")
		)
		(fp_line
			(start 0.12065 0.3048)
			(end 0.67945 0.3048)
			(stroke
				(width 0.1)
				(type default)
			)
			(layer "B.Fab")
		)
		(fp_line
			(start -0.120396 0.3048)
			(end -0.120396 0.2794)
			(stroke
				(width 0.1)
				(type default)
			)
			(layer "B.Fab")
		)
		(fp_line
			(start -0.67945 0.3048)
			(end -0.120396 0.3048)
			(stroke
				(width 0.1)
				(type default)
			)
			(layer "B.Fab")
		)
		(pad "1" smd circle
			(at 0.40005 0 270)
			(size 0 0)
			(layers "B.Cu" "B.Mask" "B.Paste")
			(net "PVNN_TERM_CPU0")
		)
		(pad "2" smd circle
			(at -0.40005 0 270)
			(size 0 0)
			(layers "B.Cu" "B.Mask" "B.Paste")
			(net "DBP_CPU_HOOK9_MBP3_GTL_QS_N")
		)
	)
)
